(kicad_pcb
	(version 20260206)
	(generator "pcbnew")
	(generator_version "10.0")
	(general
		(thickness 1.6)
		(legacy_teardrops no)
	)
	(paper "A4")
	(title_block
		(title "04192023_DAF0TMB3IC0_F0TG_MB_C_brd_V02_OCP.brd")
		(comment 1 "Grand Teton / footprint 3955 of 8354 (U25), pads 1988-2102 of 6102")
	)
	(layers
		(0 "F.Cu" signal "TOP")
		(4 "In1.Cu" signal "GND")
		(6 "In2.Cu" signal "IN1")
		(8 "In3.Cu" signal "GND1")
		(10 "In4.Cu" signal "IN2")
		(12 "In5.Cu" signal "GND2")
		(14 "In6.Cu" signal "IN3")
		(16 "In7.Cu" signal "GND3")
		(18 "In8.Cu" signal "VCC")
		(20 "In9.Cu" signal "VCC1")
		(22 "In10.Cu" signal "GND4")
		(24 "In11.Cu" signal "IN4")
		(26 "In12.Cu" signal "GND5")
		(28 "In13.Cu" signal "IN5")
		(30 "In14.Cu" signal "GND6")
		(32 "In15.Cu" signal "IN6")
		(34 "In16.Cu" signal "GND7")
		(2 "B.Cu" signal "BOTTOM")
		(9 "F.Adhes" user "F.Adhesive")
		(11 "B.Adhes" user "B.Adhesive")
		(13 "F.Paste" user "Package Geometry/Pastemask Top")
		(15 "B.Paste" user "Package Geometry/Pastemask Bottom")
		(5 "F.SilkS" user "Ref Des/Silkscreen Top")
		(7 "B.SilkS" user "Ref Des/Silkscreen Bottom")
		(1 "F.Mask" user "Board Geometry/Soldermask Top")
		(3 "B.Mask" user "Board Geometry/Soldermask Bottom")
		(17 "Dwgs.User" user "User.Drawings")
		(19 "Cmts.User" user "User.Comments")
		(21 "Eco1.User" user "User.Eco1")
		(23 "Eco2.User" user "User.Eco2")
		(25 "Edge.Cuts" user "Board Geometry/Outline")
		(27 "Margin" user)
		(31 "F.CrtYd" user "Package Geometry/Place Bound Top")
		(29 "B.CrtYd" user "Package Geometry/Place Bound Bottom")
		(35 "F.Fab" user "Ref Des/Assembly Top")
		(33 "B.Fab" user "Ref Des/Assembly Bottom")
	)
	(footprint ""
		(layer "F.Cu")
		(at 359.867962 -258.880102 180)
		(property "Reference" "U25"
			(at -45.78477 -62.086744 0)
			(unlocked yes)
			(layer "F.SilkS")
			(effects
				(font
					(size 0.7874 0.5842)
					(thickness 0.1524)
				)
			)
		)
		(property "Value" ""
			(at 0 0 180)
			(layer "F.Fab")
			(effects
				(font
					(size 1.27 1.27)
				)
			)
		)
		(duplicate_pad_numbers_are_jumpers no)
		(pad "BK11" smd circle
			(at -25.530048 5.219954 180)
			(size 0.450088 0.450088)
			(layers "F.Cu" "F.Mask" "F.Paste")
			(net "M_L_CPU0_SB_CA<5>")
		)
		(pad "BK12" smd circle
			(at -24.589994 5.219954 180)
			(size 0.450088 0.450088)
			(layers "F.Cu" "F.Mask" "F.Paste")
			(net "GND")
		)
		(pad "BK13" smd circle
			(at -23.64994 5.219954 180)
			(size 0.450088 0.450088)
			(layers "F.Cu" "F.Mask" "F.Paste")
			(net "M_H_CPU0_SB_CA<6>")
		)
		(pad "BK14" smd circle
			(at -22.709886 5.219954 180)
			(size 0.450088 0.450088)
			(layers "F.Cu" "F.Mask" "F.Paste")
			(net "M_H_CPU0_SB_CA<5>")
		)
		(pad "BK15" smd circle
			(at -21.770086 5.219954 180)
			(size 0.450088 0.450088)
			(layers "F.Cu" "F.Mask" "F.Paste")
			(net "GND")
		)
		(pad "BK16" smd circle
			(at -20.830032 5.219954 180)
			(size 0.450088 0.450088)
			(layers "F.Cu" "F.Mask" "F.Paste")
			(net "M_J_CPU0_SB_CA<6>")
		)
		(pad "BK17" smd circle
			(at -19.889978 5.219954 180)
			(size 0.450088 0.450088)
			(layers "F.Cu" "F.Mask" "F.Paste")
			(net "GND")
		)
		(pad "BK18" smd circle
			(at -18.949924 5.219954 180)
			(size 0.450088 0.450088)
			(layers "F.Cu" "F.Mask" "F.Paste")
			(net "M_J_CPU0_SB_CA<5>")
		)
		(pad "BK19" smd circle
			(at -18.010124 5.219954 180)
			(size 0.450088 0.450088)
			(layers "F.Cu" "F.Mask" "F.Paste")
			(net "GND")
		)
		(pad "BK20" smd circle
			(at -17.07007 5.219954 180)
			(size 0.450088 0.450088)
			(layers "F.Cu" "F.Mask" "F.Paste")
			(net "M_I_CPU0_SB_CA<6>")
		)
		(pad "BK21" smd circle
			(at -16.130016 5.219954 180)
			(size 0.450088 0.450088)
			(layers "F.Cu" "F.Mask" "F.Paste")
			(net "M_I_CPU0_SB_CA<5>")
		)
		(pad "BK22" smd circle
			(at -15.189962 5.219954 180)
			(size 0.450088 0.450088)
			(layers "F.Cu" "F.Mask" "F.Paste")
			(net "PVDD11_S3_P0")
		)
		(pad "BK23" smd circle
			(at -14.249908 5.219954 180)
			(size 0.450088 0.450088)
			(layers "F.Cu" "F.Mask" "F.Paste")
			(net "GND")
		)
		(pad "BK24" smd circle
			(at -13.310108 5.219954 180)
			(size 0.450088 0.450088)
			(layers "F.Cu" "F.Mask" "F.Paste")
			(net "PVDD11_S3_P0")
		)
		(pad "BK25" smd circle
			(at -12.370054 5.219954 180)
			(size 0.450088 0.450088)
			(layers "F.Cu" "F.Mask" "F.Paste")
			(net "GND")
		)
		(pad "BK26" smd circle
			(at -11.43 5.219954 180)
			(size 0.450088 0.450088)
			(layers "F.Cu" "F.Mask" "F.Paste")
			(net "PVDD11_S3_P0")
		)
		(pad "BK27" smd circle
			(at -10.489946 5.219954 180)
			(size 0.450088 0.450088)
			(layers "F.Cu" "F.Mask" "F.Paste")
			(net "GND")
		)
		(pad "BK28" smd circle
			(at -9.549892 5.219954 180)
			(size 0.450088 0.450088)
			(layers "F.Cu" "F.Mask" "F.Paste")
			(net "PVDD11_S3_P0")
		)
		(pad "BK48" smd circle
			(at 9.249918 5.219954 180)
			(size 0.450088 0.450088)
			(layers "F.Cu" "F.Mask" "F.Paste")
			(net "GND")
		)
		(pad "BK49" smd circle
			(at 10.189972 5.219954 180)
			(size 0.450088 0.450088)
			(layers "F.Cu" "F.Mask" "F.Paste")
			(net "PVDD11_S3_P0")
		)
		(pad "BK50" smd circle
			(at 11.130026 5.219954 180)
			(size 0.450088 0.450088)
			(layers "F.Cu" "F.Mask" "F.Paste")
			(net "GND")
		)
		(pad "BK51" smd circle
			(at 12.07008 5.219954 180)
			(size 0.450088 0.450088)
			(layers "F.Cu" "F.Mask" "F.Paste")
			(net "PVDDIO_P0")
		)
		(pad "BK52" smd circle
			(at 13.00988 5.219954 180)
			(size 0.450088 0.450088)
			(layers "F.Cu" "F.Mask" "F.Paste")
			(net "GND")
		)
		(pad "BK53" smd circle
			(at 13.949934 5.219954 180)
			(size 0.450088 0.450088)
			(layers "F.Cu" "F.Mask" "F.Paste")
			(net "PVDDIO_P0")
		)
		(pad "BK54" smd circle
			(at 14.889988 5.219954 180)
			(size 0.450088 0.450088)
			(layers "F.Cu" "F.Mask" "F.Paste")
			(net "GND")
		)
		(pad "BK55" smd circle
			(at 15.830042 5.219954 180)
			(size 0.450088 0.450088)
			(layers "F.Cu" "F.Mask" "F.Paste")
			(net "M_C_CPU0_SB_CA<5>")
		)
		(pad "BK56" smd circle
			(at 16.770096 5.219954 180)
			(size 0.450088 0.450088)
			(layers "F.Cu" "F.Mask" "F.Paste")
			(net "M_C_CPU0_SB_CA<6>")
		)
		(pad "BK57" smd circle
			(at 17.709896 5.219954 180)
			(size 0.450088 0.450088)
			(layers "F.Cu" "F.Mask" "F.Paste")
			(net "GND")
		)
		(pad "BK58" smd circle
			(at 18.64995 5.219954 180)
			(size 0.450088 0.450088)
			(layers "F.Cu" "F.Mask" "F.Paste")
			(net "M_D_CPU0_SB_CA<5>")
		)
		(pad "BK59" smd circle
			(at 19.590004 5.219954 180)
			(size 0.450088 0.450088)
			(layers "F.Cu" "F.Mask" "F.Paste")
			(net "GND")
		)
		(pad "BK60" smd circle
			(at 20.530058 5.219954 180)
			(size 0.450088 0.450088)
			(layers "F.Cu" "F.Mask" "F.Paste")
			(net "M_D_CPU0_SB_CA<6>")
		)
		(pad "BK61" smd circle
			(at 21.470112 5.219954 180)
			(size 0.450088 0.450088)
			(layers "F.Cu" "F.Mask" "F.Paste")
			(net "GND")
		)
		(pad "BK62" smd circle
			(at 22.409912 5.219954 180)
			(size 0.450088 0.450088)
			(layers "F.Cu" "F.Mask" "F.Paste")
			(net "M_B_CPU0_SB_CA<5>")
		)
		(pad "BK63" smd circle
			(at 23.349966 5.219954 180)
			(size 0.450088 0.450088)
			(layers "F.Cu" "F.Mask" "F.Paste")
			(net "M_B_CPU0_SB_CA<6>")
		)
		(pad "BK64" smd circle
			(at 24.29002 5.219954 180)
			(size 0.450088 0.450088)
			(layers "F.Cu" "F.Mask" "F.Paste")
			(net "GND")
		)
		(pad "BK65" smd circle
			(at 25.230074 5.219954 180)
			(size 0.450088 0.450088)
			(layers "F.Cu" "F.Mask" "F.Paste")
			(net "M_F_CPU0_SB_CA<5>")
		)
		(pad "BK66" smd circle
			(at 26.170128 5.219954 180)
			(size 0.450088 0.450088)
			(layers "F.Cu" "F.Mask" "F.Paste")
			(net "GND")
		)
		(pad "BK67" smd circle
			(at 27.109928 5.219954 180)
			(size 0.450088 0.450088)
			(layers "F.Cu" "F.Mask" "F.Paste")
			(net "M_F_CPU0_SB_CA<6>")
		)
		(pad "BK68" smd circle
			(at 28.049982 5.219954 180)
			(size 0.450088 0.450088)
			(layers "F.Cu" "F.Mask" "F.Paste")
			(net "GND")
		)
		(pad "BK69" smd circle
			(at 28.990036 5.219954 180)
			(size 0.450088 0.450088)
			(layers "F.Cu" "F.Mask" "F.Paste")
			(net "M_E_CPU0_SB_CA<5>")
		)
		(pad "BK70" smd circle
			(at 29.93009 5.219954 180)
			(size 0.450088 0.450088)
			(layers "F.Cu" "F.Mask" "F.Paste")
			(net "M_E_CPU0_SB_CA<6>")
		)
		(pad "BK71" smd circle
			(at 30.86989 5.219954 180)
			(size 0.450088 0.450088)
			(layers "F.Cu" "F.Mask" "F.Paste")
			(net "GND")
		)
		(pad "BK72" smd circle
			(at 31.809944 5.219954 180)
			(size 0.450088 0.450088)
			(layers "F.Cu" "F.Mask" "F.Paste")
			(net "M_A_CPU0_SB_CA<5>")
		)
		(pad "BK73" smd circle
			(at 32.749998 5.219954 180)
			(size 0.450088 0.450088)
			(layers "F.Cu" "F.Mask" "F.Paste")
			(net "GND")
		)
		(pad "BK74" smd circle
			(at 33.690052 5.219954 180)
			(size 0.450088 0.450088)
			(layers "F.Cu" "F.Mask" "F.Paste")
			(net "M_A_CPU0_SB_CA<6>")
		)
		(pad "BL1" smd circle
			(at -34.459926 6.02996 180)
			(size 0.450088 0.450088)
			(layers "F.Cu" "F.Mask" "F.Paste")
			(net "GND")
		)
		(pad "BL2" smd circle
			(at -33.519872 6.02996 180)
			(size 0.450088 0.450088)
			(layers "F.Cu" "F.Mask" "F.Paste")
			(net "Net_1840")
		)
		(pad "BL3" smd circle
			(at -32.580072 6.02996 180)
			(size 0.450088 0.450088)
			(layers "F.Cu" "F.Mask" "F.Paste")
			(net "M_G_CPU0_SB_PAR")
		)
		(pad "BL4" smd circle
			(at -31.640018 6.02996 180)
			(size 0.450088 0.450088)
			(layers "F.Cu" "F.Mask" "F.Paste")
			(net "GND")
		)
		(pad "BL5" smd circle
			(at -30.699964 6.02996 180)
			(size 0.450088 0.450088)
			(layers "F.Cu" "F.Mask" "F.Paste")
			(net "Net_1969")
		)
		(pad "BL6" smd circle
			(at -29.75991 6.02996 180)
			(size 0.450088 0.450088)
			(layers "F.Cu" "F.Mask" "F.Paste")
			(net "GND")
		)
		(pad "BL7" smd circle
			(at -28.82011 6.02996 180)
			(size 0.450088 0.450088)
			(layers "F.Cu" "F.Mask" "F.Paste")
			(net "M_K_CPU0_SB_PAR")
		)
		(pad "BL8" smd circle
			(at -27.880056 6.02996 180)
			(size 0.450088 0.450088)
			(layers "F.Cu" "F.Mask" "F.Paste")
			(net "GND")
		)
		(pad "BL9" smd circle
			(at -26.940002 6.02996 180)
			(size 0.450088 0.450088)
			(layers "F.Cu" "F.Mask" "F.Paste")
			(net "Net_1961")
		)
		(pad "BL10" smd circle
			(at -25.999948 6.02996 180)
			(size 0.450088 0.450088)
			(layers "F.Cu" "F.Mask" "F.Paste")
			(net "M_L_CPU0_SB_PAR")
		)
		(pad "BL11" smd circle
			(at -25.059894 6.02996 180)
			(size 0.450088 0.450088)
			(layers "F.Cu" "F.Mask" "F.Paste")
			(net "GND")
		)
		(pad "BL12" smd circle
			(at -24.120094 6.02996 180)
			(size 0.450088 0.450088)
			(layers "F.Cu" "F.Mask" "F.Paste")
			(net "Net_1848")
		)
		(pad "BL13" smd circle
			(at -23.18004 6.02996 180)
			(size 0.450088 0.450088)
			(layers "F.Cu" "F.Mask" "F.Paste")
			(net "GND")
		)
		(pad "BL14" smd circle
			(at -22.239986 6.02996 180)
			(size 0.450088 0.450088)
			(layers "F.Cu" "F.Mask" "F.Paste")
			(net "M_H_CPU0_SB_PAR")
		)
		(pad "BL15" smd circle
			(at -21.299932 6.02996 180)
			(size 0.450088 0.450088)
			(layers "F.Cu" "F.Mask" "F.Paste")
			(net "GND")
		)
		(pad "BL16" smd circle
			(at -20.359878 6.02996 180)
			(size 0.450088 0.450088)
			(layers "F.Cu" "F.Mask" "F.Paste")
			(net "Net_1864")
		)
		(pad "BL17" smd circle
			(at -19.420078 6.02996 180)
			(size 0.450088 0.450088)
			(layers "F.Cu" "F.Mask" "F.Paste")
			(net "M_J_CPU0_SB_PAR")
		)
		(pad "BL18" smd circle
			(at -18.480024 6.02996 180)
			(size 0.450088 0.450088)
			(layers "F.Cu" "F.Mask" "F.Paste")
			(net "GND")
		)
		(pad "BL19" smd circle
			(at -17.53997 6.02996 180)
			(size 0.450088 0.450088)
			(layers "F.Cu" "F.Mask" "F.Paste")
			(net "Net_1856")
		)
		(pad "BL20" smd circle
			(at -16.599916 6.02996 180)
			(size 0.450088 0.450088)
			(layers "F.Cu" "F.Mask" "F.Paste")
			(net "GND")
		)
		(pad "BL21" smd circle
			(at -15.660116 6.02996 180)
			(size 0.450088 0.450088)
			(layers "F.Cu" "F.Mask" "F.Paste")
			(net "M_I_CPU0_SB_PAR")
		)
		(pad "BL22" smd circle
			(at -14.720062 6.02996 180)
			(size 0.450088 0.450088)
			(layers "F.Cu" "F.Mask" "F.Paste")
			(net "GND")
		)
		(pad "BL23" smd circle
			(at -13.780008 6.02996 180)
			(size 0.450088 0.450088)
			(layers "F.Cu" "F.Mask" "F.Paste")
			(net "PVDD11_S3_P0")
		)
		(pad "BL24" smd circle
			(at -12.839954 6.02996 180)
			(size 0.450088 0.450088)
			(layers "F.Cu" "F.Mask" "F.Paste")
			(net "GND")
		)
		(pad "BL25" smd circle
			(at -11.8999 6.02996 180)
			(size 0.450088 0.450088)
			(layers "F.Cu" "F.Mask" "F.Paste")
			(net "PVDD11_S3_P0")
		)
		(pad "BL26" smd circle
			(at -10.9601 6.02996 180)
			(size 0.450088 0.450088)
			(layers "F.Cu" "F.Mask" "F.Paste")
			(net "GND")
		)
		(pad "BL27" smd circle
			(at -10.020046 6.02996 180)
			(size 0.450088 0.450088)
			(layers "F.Cu" "F.Mask" "F.Paste")
			(net "PVDD11_S3_P0")
		)
		(pad "BL28" smd circle
			(at -9.079992 6.02996 180)
			(size 0.450088 0.450088)
			(layers "F.Cu" "F.Mask" "F.Paste")
			(net "GND")
		)
		(pad "BL48" smd circle
			(at 8.780018 6.02996 180)
			(size 0.450088 0.450088)
			(layers "F.Cu" "F.Mask" "F.Paste")
			(net "PVDD11_S3_P0")
		)
		(pad "BL49" smd circle
			(at 9.720072 6.02996 180)
			(size 0.450088 0.450088)
			(layers "F.Cu" "F.Mask" "F.Paste")
			(net "GND")
		)
		(pad "BL50" smd circle
			(at 10.659872 6.02996 180)
			(size 0.450088 0.450088)
			(layers "F.Cu" "F.Mask" "F.Paste")
			(net "PVDDIO_P0")
		)
		(pad "BL51" smd circle
			(at 11.599926 6.02996 180)
			(size 0.450088 0.450088)
			(layers "F.Cu" "F.Mask" "F.Paste")
			(net "GND")
		)
		(pad "BL52" smd circle
			(at 12.53998 6.02996 180)
			(size 0.450088 0.450088)
			(layers "F.Cu" "F.Mask" "F.Paste")
			(net "PVDDIO_P0")
		)
		(pad "BL53" smd circle
			(at 13.480034 6.02996 180)
			(size 0.450088 0.450088)
			(layers "F.Cu" "F.Mask" "F.Paste")
			(net "GND")
		)
		(pad "BL54" smd circle
			(at 14.420088 6.02996 180)
			(size 0.450088 0.450088)
			(layers "F.Cu" "F.Mask" "F.Paste")
			(net "PVDDIO_P0")
		)
		(pad "BL55" smd circle
			(at 15.359888 6.02996 180)
			(size 0.450088 0.450088)
			(layers "F.Cu" "F.Mask" "F.Paste")
			(net "Net_1808")
		)
		(pad "BL56" smd circle
			(at 16.299942 6.02996 180)
			(size 0.450088 0.450088)
			(layers "F.Cu" "F.Mask" "F.Paste")
			(net "GND")
		)
		(pad "BL57" smd circle
			(at 17.239996 6.02996 180)
			(size 0.450088 0.450088)
			(layers "F.Cu" "F.Mask" "F.Paste")
			(net "M_C_CPU0_SB_PAR")
		)
		(pad "BL58" smd circle
			(at 18.18005 6.02996 180)
			(size 0.450088 0.450088)
			(layers "F.Cu" "F.Mask" "F.Paste")
			(net "GND")
		)
		(pad "BL59" smd circle
			(at 19.120104 6.02996 180)
			(size 0.450088 0.450088)
			(layers "F.Cu" "F.Mask" "F.Paste")
			(net "Net_1816")
		)
		(pad "BL60" smd circle
			(at 20.059904 6.02996 180)
			(size 0.450088 0.450088)
			(layers "F.Cu" "F.Mask" "F.Paste")
			(net "M_D_CPU0_SB_PAR")
		)
		(pad "BL61" smd circle
			(at 20.999958 6.02996 180)
			(size 0.450088 0.450088)
			(layers "F.Cu" "F.Mask" "F.Paste")
			(net "GND")
		)
		(pad "BL62" smd circle
			(at 21.940012 6.02996 180)
			(size 0.450088 0.450088)
			(layers "F.Cu" "F.Mask" "F.Paste")
			(net "Net_1800")
		)
		(pad "BL63" smd circle
			(at 22.880066 6.02996 180)
			(size 0.450088 0.450088)
			(layers "F.Cu" "F.Mask" "F.Paste")
			(net "GND")
		)
		(pad "BL64" smd circle
			(at 23.82012 6.02996 180)
			(size 0.450088 0.450088)
			(layers "F.Cu" "F.Mask" "F.Paste")
			(net "M_B_CPU0_SB_PAR")
		)
		(pad "BL65" smd circle
			(at 24.75992 6.02996 180)
			(size 0.450088 0.450088)
			(layers "F.Cu" "F.Mask" "F.Paste")
			(net "GND")
		)
		(pad "BL66" smd circle
			(at 25.699974 6.02996 180)
			(size 0.450088 0.450088)
			(layers "F.Cu" "F.Mask" "F.Paste")
			(net "Net_1832")
		)
		(pad "BL67" smd circle
			(at 26.640028 6.02996 180)
			(size 0.450088 0.450088)
			(layers "F.Cu" "F.Mask" "F.Paste")
			(net "M_F_CPU0_SB_PAR")
		)
		(pad "BL68" smd circle
			(at 27.580082 6.02996 180)
			(size 0.450088 0.450088)
			(layers "F.Cu" "F.Mask" "F.Paste")
			(net "GND")
		)
		(pad "BL69" smd circle
			(at 28.519882 6.02996 180)
			(size 0.450088 0.450088)
			(layers "F.Cu" "F.Mask" "F.Paste")
			(net "Net_1824")
		)
		(pad "BL70" smd circle
			(at 29.459936 6.02996 180)
			(size 0.450088 0.450088)
			(layers "F.Cu" "F.Mask" "F.Paste")
			(net "GND")
		)
		(pad "BL71" smd circle
			(at 30.39999 6.02996 180)
			(size 0.450088 0.450088)
			(layers "F.Cu" "F.Mask" "F.Paste")
			(net "M_E_CPU0_SB_PAR")
		)
		(pad "BL72" smd circle
			(at 31.340044 6.02996 180)
			(size 0.450088 0.450088)
			(layers "F.Cu" "F.Mask" "F.Paste")
			(net "GND")
		)
		(pad "BL73" smd circle
			(at 32.280098 6.02996 180)
			(size 0.450088 0.450088)
			(layers "F.Cu" "F.Mask" "F.Paste")
			(net "Net_1792")
		)
		(pad "BL74" smd circle
			(at 33.219898 6.02996 180)
			(size 0.450088 0.450088)
			(layers "F.Cu" "F.Mask" "F.Paste")
			(net "M_A_CPU0_SB_PAR")
		)
		(pad "BL75" smd circle
			(at 34.159952 6.02996 180)
			(size 0.450088 0.450088)
			(layers "F.Cu" "F.Mask" "F.Paste")
			(net "GND")
		)
		(pad "BM2" smd circle
			(at -33.990026 6.839966 180)
			(size 0.450088 0.450088)
			(layers "F.Cu" "F.Mask" "F.Paste")
			(net "Net_1841")
		)
		(pad "BM3" smd circle
			(at -33.049972 6.839966 180)
			(size 0.450088 0.450088)
			(layers "F.Cu" "F.Mask" "F.Paste")
			(net "GND")
		)
		(pad "BM4" smd circle
			(at -32.109918 6.839966 180)
			(size 0.450088 0.450088)
			(layers "F.Cu" "F.Mask" "F.Paste")
			(net "M_G_CPU0_SB_CS_N<0>")
		)
		(pad "BM5" smd circle
			(at -31.170118 6.839966 180)
			(size 0.450088 0.450088)
			(layers "F.Cu" "F.Mask" "F.Paste")
			(net "PVDDCR_SOC_P0")
		)
		(pad "BM6" smd circle
			(at -30.230064 6.839966 180)
			(size 0.450088 0.450088)
			(layers "F.Cu" "F.Mask" "F.Paste")
			(net "Net_1970")
		)
		(pad "BM7" smd circle
			(at -29.29001 6.839966 180)
			(size 0.450088 0.450088)
			(layers "F.Cu" "F.Mask" "F.Paste")
			(net "M_K_CPU0_SB_CS_N<0>")
		)
		(pad "BM8" smd circle
			(at -28.349956 6.839966 180)
			(size 0.450088 0.450088)
			(layers "F.Cu" "F.Mask" "F.Paste")
			(net "GND")
		)
		(pad "BM9" smd circle
			(at -27.409902 6.839966 180)
			(size 0.450088 0.450088)
			(layers "F.Cu" "F.Mask" "F.Paste")
			(net "Net_1962")
		)
		(pad "BM10" smd circle
			(at -26.470102 6.839966 180)
			(size 0.450088 0.450088)
			(layers "F.Cu" "F.Mask" "F.Paste")
			(net "GND")
		)
		(pad "BM11" smd circle
			(at -25.530048 6.839966 180)
			(size 0.450088 0.450088)
			(layers "F.Cu" "F.Mask" "F.Paste")
			(net "M_L_CPU0_SB_CS_N<0>")
		)
		(pad "BM12" smd circle
			(at -24.589994 6.839966 180)
			(size 0.450088 0.450088)
			(layers "F.Cu" "F.Mask" "F.Paste")
			(net "PVDD11_S3_P0")
		)
		(pad "BM13" smd circle
			(at -23.64994 6.839966 180)
			(size 0.450088 0.450088)
			(layers "F.Cu" "F.Mask" "F.Paste")
			(net "Net_1849")
		)
		(pad "BM14" smd circle
			(at -22.709886 6.839966 180)
			(size 0.450088 0.450088)
			(layers "F.Cu" "F.Mask" "F.Paste")
			(net "M_H_CPU0_SB_CS_N<0>")
		)
		(pad "BM15" smd circle
			(at -21.770086 6.839966 180)
			(size 0.450088 0.450088)
			(layers "F.Cu" "F.Mask" "F.Paste")
			(net "GND")
		)
	)
)
